(kicad_pcb
	(version 20260206)
	(generator "pcbnew")
	(generator_version "10.0")
	(general
		(thickness 1.6)
		(legacy_teardrops no)
	)
	(paper "A4")
	(title_block
		(title "04192023_DAF0TMB3IC0_F0TG_MB_C_brd_V02_OCP.brd")
		(comment 1 "Grand Teton / footprints 1650-1656 of 8354")
	)
	(layers
		(0 "F.Cu" signal "TOP")
		(4 "In1.Cu" signal "GND")
		(6 "In2.Cu" signal "IN1")
		(8 "In3.Cu" signal "GND1")
		(10 "In4.Cu" signal "IN2")
		(12 "In5.Cu" signal "GND2")
		(14 "In6.Cu" signal "IN3")
		(16 "In7.Cu" signal "GND3")
		(18 "In8.Cu" signal "VCC")
		(20 "In9.Cu" signal "VCC1")
		(22 "In10.Cu" signal "GND4")
		(24 "In11.Cu" signal "IN4")
		(26 "In12.Cu" signal "GND5")
		(28 "In13.Cu" signal "IN5")
		(30 "In14.Cu" signal "GND6")
		(32 "In15.Cu" signal "IN6")
		(34 "In16.Cu" signal "GND7")
		(2 "B.Cu" signal "BOTTOM")
		(9 "F.Adhes" user "F.Adhesive")
		(11 "B.Adhes" user "B.Adhesive")
		(13 "F.Paste" user "Package Geometry/Pastemask Top")
		(15 "B.Paste" user "Package Geometry/Pastemask Bottom")
		(5 "F.SilkS" user "Ref Des/Silkscreen Top")
		(7 "B.SilkS" user "Ref Des/Silkscreen Bottom")
		(1 "F.Mask" user "Board Geometry/Soldermask Top")
		(3 "B.Mask" user "Board Geometry/Soldermask Bottom")
		(17 "Dwgs.User" user "User.Drawings")
		(19 "Cmts.User" user "User.Comments")
		(21 "Eco1.User" user "User.Eco1")
		(23 "Eco2.User" user "User.Eco2")
		(25 "Edge.Cuts" user "Board Geometry/Outline")
		(27 "Margin" user)
		(31 "F.CrtYd" user "Package Geometry/Place Bound Top")
		(29 "B.CrtYd" user "Package Geometry/Place Bound Bottom")
		(35 "F.Fab" user "Ref Des/Assembly Top")
		(33 "B.Fab" user "Ref Des/Assembly Bottom")
	)
	(footprint ""
		(layer "F.Cu")
		(at 197.269608 -119.975376)
		(property "Reference" "R798"
			(at 0 0 0)
			(layer "F.SilkS")
			(hide yes)
			(effects
				(font
					(size 1.27 1.27)
				)
			)
		)
		(property "Value" ""
			(at 0 0 0)
			(layer "F.Fab")
			(effects
				(font
					(size 1.27 1.27)
				)
			)
		)
		(duplicate_pad_numbers_are_jumpers no)
		(fp_line
			(start -0.7874 -0.4064)
			(end 0.7874 -0.4064)
			(stroke
				(width 0.1524)
				(type default)
			)
			(layer "F.SilkS")
		)
		(fp_line
			(start -0.7874 0.4064)
			(end -0.7874 -0.4064)
			(stroke
				(width 0.1524)
				(type default)
			)
			(layer "F.SilkS")
		)
		(fp_line
			(start 0.7874 -0.4064)
			(end 0.7874 0.4064)
			(stroke
				(width 0.1524)
				(type default)
			)
			(layer "F.SilkS")
		)
		(fp_line
			(start 0.7874 0.4064)
			(end -0.7874 0.4064)
			(stroke
				(width 0.1524)
				(type default)
			)
			(layer "F.SilkS")
		)
		(fp_line
			(start -0.67945 -0.305054)
			(end -0.12065 -0.305054)
			(stroke
				(width 0.1)
				(type default)
			)
			(layer "F.Fab")
		)
		(fp_line
			(start -0.67945 0.3048)
			(end -0.67945 -0.305054)
			(stroke
				(width 0.1)
				(type default)
			)
			(layer "F.Fab")
		)
		(fp_line
			(start -0.12065 -0.305054)
			(end -0.12065 -0.2794)
			(stroke
				(width 0.1)
				(type default)
			)
			(layer "F.Fab")
		)
		(fp_line
			(start -0.12065 -0.2794)
			(end 0.12065 -0.2794)
			(stroke
				(width 0.1)
				(type default)
			)
			(layer "F.Fab")
		)
		(fp_line
			(start -0.12065 0.2794)
			(end -0.12065 0.3048)
			(stroke
				(width 0.1)
				(type default)
			)
			(layer "F.Fab")
		)
		(fp_line
			(start -0.12065 0.3048)
			(end -0.67945 0.3048)
			(stroke
				(width 0.1)
				(type default)
			)
			(layer "F.Fab")
		)
		(fp_line
			(start 0.120396 0.2794)
			(end -0.12065 0.2794)
			(stroke
				(width 0.1)
				(type default)
			)
			(layer "F.Fab")
		)
		(fp_line
			(start 0.120396 0.3048)
			(end 0.120396 0.2794)
			(stroke
				(width 0.1)
				(type default)
			)
			(layer "F.Fab")
		)
		(fp_line
			(start 0.12065 -0.3048)
			(end 0.67945 -0.3048)
			(stroke
				(width 0.1)
				(type default)
			)
			(layer "F.Fab")
		)
		(fp_line
			(start 0.12065 -0.2794)
			(end 0.12065 -0.3048)
			(stroke
				(width 0.1)
				(type default)
			)
			(layer "F.Fab")
		)
		(fp_line
			(start 0.67945 -0.3048)
			(end 0.67945 0.3048)
			(stroke
				(width 0.1)
				(type default)
			)
			(layer "F.Fab")
		)
		(fp_line
			(start 0.67945 0.3048)
			(end 0.120396 0.3048)
			(stroke
				(width 0.1)
				(type default)
			)
			(layer "F.Fab")
		)
		(pad "1" smd circle
			(at -0.40005 0)
			(size 0 0)
			(layers "F.Cu" "F.Mask" "F.Paste")
			(net "RST_PERST_M2_0_R_N")
		)
		(pad "2" smd circle
			(at 0.40005 0)
			(size 0 0)
			(layers "F.Cu" "F.Mask" "F.Paste")
			(net "RST_PERST_M2_0_N")
		)
	)
	(footprint ""
		(layer "F.Cu")
		(at 314.475876 -70.098412 90)
		(property "Reference" "D98"
			(at -3.934714 -0.691642 90)
			(unlocked yes)
			(layer "F.SilkS")
			(effects
				(font
					(size 0.7874 0.5842)
					(thickness 0.1524)
				)
				(justify left)
			)
		)
		(property "Value" ""
			(at 0 0 90)
			(layer "F.Fab")
			(effects
				(font
					(size 1.27 1.27)
				)
			)
		)
		(duplicate_pad_numbers_are_jumpers no)
		(fp_line
			(start 1.16078 -0.4826)
			(end 1.16078 0.4826)
			(stroke
				(width 0.1524)
				(type default)
			)
			(layer "F.SilkS")
		)
		(fp_line
			(start 1.03378 -0.4826)
			(end 1.03378 0.4826)
			(stroke
				(width 0.1524)
				(type default)
			)
			(layer "F.SilkS")
		)
		(fp_line
			(start 0.90678 -0.4826)
			(end 0.90678 0.4826)
			(stroke
				(width 0.1524)
				(type default)
			)
			(layer "F.SilkS")
		)
		(fp_line
			(start -0.64008 -0.4826)
			(end 1.16078 -0.4826)
			(stroke
				(width 0.1524)
				(type default)
			)
			(layer "F.SilkS")
		)
		(fp_line
			(start -0.79248 -0.4826)
			(end 1.03378 -0.4826)
			(stroke
				(width 0.1524)
				(type default)
			)
			(layer "F.SilkS")
		)
		(fp_line
			(start -0.89408 -0.4826)
			(end 0.90678 -0.4826)
			(stroke
				(width 0.1524)
				(type default)
			)
			(layer "F.SilkS")
		)
		(fp_line
			(start 1.16078 0.4826)
			(end -0.64008 0.4826)
			(stroke
				(width 0.1524)
				(type default)
			)
			(layer "F.SilkS")
		)
		(fp_line
			(start 1.03378 0.4826)
			(end -0.79248 0.4826)
			(stroke
				(width 0.1524)
				(type default)
			)
			(layer "F.SilkS")
		)
		(fp_line
			(start 0.90678 0.4826)
			(end -0.90678 0.4826)
			(stroke
				(width 0.1524)
				(type default)
			)
			(layer "F.SilkS")
		)
		(fp_line
			(start -0.90678 0.4826)
			(end -0.90678 -0.4699)
			(stroke
				(width 0.1524)
				(type default)
			)
			(layer "F.SilkS")
		)
		(fp_line
			(start 0.499872 -0.249936)
			(end 0.499872 0.249936)
			(stroke
				(width 0.1)
				(type default)
			)
			(layer "F.Fab")
		)
		(fp_line
			(start -0.499872 -0.249936)
			(end 0.499872 -0.249936)
			(stroke
				(width 0.1)
				(type default)
			)
			(layer "F.Fab")
		)
		(fp_line
			(start 0.499872 0.249936)
			(end -0.499872 0.249936)
			(stroke
				(width 0.1)
				(type default)
			)
			(layer "F.Fab")
		)
		(fp_line
			(start -0.499872 0.249936)
			(end -0.499872 -0.249936)
			(stroke
				(width 0.1)
				(type default)
			)
			(layer "F.Fab")
		)
		(pad "A" smd rect
			(at -0.47498 0 90)
			(size 0.6096 0.7112)
			(layers "F.Cu" "F.Mask" "F.Paste")
			(net "LED_P5V")
		)
		(pad "C" smd rect
			(at 0.47498 0 90)
			(size 0.6096 0.7112)
			(layers "F.Cu" "F.Mask" "F.Paste")
			(net "GND")
		)
	)
	(footprint ""
		(layer "F.Cu")
		(at 318.262 -362.839 -90)
		(property "Reference" "PR74"
			(at 0 0 270)
			(layer "F.SilkS")
			(hide yes)
			(effects
				(font
					(size 1.27 1.27)
				)
			)
		)
		(property "Value" ""
			(at 0 0 270)
			(layer "F.Fab")
			(effects
				(font
					(size 1.27 1.27)
				)
			)
		)
		(duplicate_pad_numbers_are_jumpers no)
		(fp_line
			(start -0.7874 0.4064)
			(end -0.7874 -0.4064)
			(stroke
				(width 0.1524)
				(type default)
			)
			(layer "F.SilkS")
		)
		(fp_line
			(start 0.7874 0.4064)
			(end -0.7874 0.4064)
			(stroke
				(width 0.1524)
				(type default)
			)
			(layer "F.SilkS")
		)
		(fp_line
			(start -0.7874 -0.4064)
			(end 0.7874 -0.4064)
			(stroke
				(width 0.1524)
				(type default)
			)
			(layer "F.SilkS")
		)
		(fp_line
			(start 0.7874 -0.4064)
			(end 0.7874 0.4064)
			(stroke
				(width 0.1524)
				(type default)
			)
			(layer "F.SilkS")
		)
		(fp_line
			(start -0.67945 0.3048)
			(end -0.67945 -0.305054)
			(stroke
				(width 0.1)
				(type default)
			)
			(layer "F.Fab")
		)
		(fp_line
			(start -0.12065 0.3048)
			(end -0.67945 0.3048)
			(stroke
				(width 0.1)
				(type default)
			)
			(layer "F.Fab")
		)
		(fp_line
			(start 0.120396 0.3048)
			(end 0.120396 0.2794)
			(stroke
				(width 0.1)
				(type default)
			)
			(layer "F.Fab")
		)
		(fp_line
			(start 0.67945 0.3048)
			(end 0.120396 0.3048)
			(stroke
				(width 0.1)
				(type default)
			)
			(layer "F.Fab")
		)
		(fp_line
			(start -0.12065 0.2794)
			(end -0.12065 0.3048)
			(stroke
				(width 0.1)
				(type default)
			)
			(layer "F.Fab")
		)
		(fp_line
			(start 0.120396 0.2794)
			(end -0.12065 0.2794)
			(stroke
				(width 0.1)
				(type default)
			)
			(layer "F.Fab")
		)
		(fp_line
			(start -0.12065 -0.2794)
			(end 0.12065 -0.2794)
			(stroke
				(width 0.1)
				(type default)
			)
			(layer "F.Fab")
		)
		(fp_line
			(start 0.12065 -0.2794)
			(end 0.12065 -0.3048)
			(stroke
				(width 0.1)
				(type default)
			)
			(layer "F.Fab")
		)
		(fp_line
			(start 0.12065 -0.3048)
			(end 0.67945 -0.3048)
			(stroke
				(width 0.1)
				(type default)
			)
			(layer "F.Fab")
		)
		(fp_line
			(start 0.67945 -0.3048)
			(end 0.67945 0.3048)
			(stroke
				(width 0.1)
				(type default)
			)
			(layer "F.Fab")
		)
		(fp_line
			(start -0.67945 -0.305054)
			(end -0.12065 -0.305054)
			(stroke
				(width 0.1)
				(type default)
			)
			(layer "F.Fab")
		)
		(fp_line
			(start -0.12065 -0.305054)
			(end -0.12065 -0.2794)
			(stroke
				(width 0.1)
				(type default)
			)
			(layer "F.Fab")
		)
		(pad "1" smd circle
			(at -0.40005 0 270)
			(size 0 0)
			(layers "F.Cu" "F.Mask" "F.Paste")
			(net "P12V_AUX")
		)
		(pad "2" smd circle
			(at 0.40005 0 270)
			(size 0 0)
			(layers "F.Cu" "F.Mask" "F.Paste")
			(net "PVDDCR_CPU1_P0_VINSEN")
		)
	)
	(footprint ""
		(layer "F.Cu")
		(at 366.06734 -389.86206 180)
		(property "Reference" "C900"
			(at 0 0 180)
			(layer "F.SilkS")
			(hide yes)
			(effects
				(font
					(size 1.27 1.27)
				)
			)
		)
		(property "Value" ""
			(at 0 0 180)
			(layer "F.Fab")
			(effects
				(font
					(size 1.27 1.27)
				)
			)
		)
		(duplicate_pad_numbers_are_jumpers no)
		(fp_line
			(start 0.299974 0.150114)
			(end -0.299974 0.150114)
			(stroke
				(width 0.1)
				(type default)
			)
			(layer "F.Fab")
		)
		(fp_line
			(start 0.299974 -0.150114)
			(end 0.299974 0.150114)
			(stroke
				(width 0.1)
				(type default)
			)
			(layer "F.Fab")
		)
		(fp_line
			(start -0.299974 0.150114)
			(end -0.299974 -0.150114)
			(stroke
				(width 0.1)
				(type default)
			)
			(layer "F.Fab")
		)
		(fp_line
			(start -0.299974 -0.150114)
			(end 0.299974 -0.150114)
			(stroke
				(width 0.1)
				(type default)
			)
			(layer "F.Fab")
		)
		(pad "1" smd rect
			(at -0.2667 0 180)
			(size 0.3048 0.381)
			(layers "F.Cu" "F.Mask" "F.Paste")
			(net "P5E_CPU0_P3_TX_C_DN<0>")
		)
		(pad "2" smd rect
			(at 0.2667 0 180)
			(size 0.3048 0.381)
			(layers "F.Cu" "F.Mask" "F.Paste")
			(net "P5E_CPU0_P3_TX_DN<0>")
		)
	)
	(footprint ""
		(layer "F.Cu")
		(at 273.378676 -118.618 180)
		(property "Reference" "R1341"
			(at 0 0 180)
			(layer "F.SilkS")
			(hide yes)
			(effects
				(font
					(size 1.27 1.27)
				)
			)
		)
		(property "Value" ""
			(at 0 0 180)
			(layer "F.Fab")
			(effects
				(font
					(size 1.27 1.27)
				)
			)
		)
		(duplicate_pad_numbers_are_jumpers no)
		(fp_line
			(start 0.7874 0.4064)
			(end -0.7874 0.4064)
			(stroke
				(width 0.1524)
				(type default)
			)
			(layer "F.SilkS")
		)
		(fp_line
			(start 0.7874 -0.4064)
			(end 0.7874 0.4064)
			(stroke
				(width 0.1524)
				(type default)
			)
			(layer "F.SilkS")
		)
		(fp_line
			(start -0.7874 0.4064)
			(end -0.7874 -0.4064)
			(stroke
				(width 0.1524)
				(type default)
			)
			(layer "F.SilkS")
		)
		(fp_line
			(start -0.7874 -0.4064)
			(end 0.7874 -0.4064)
			(stroke
				(width 0.1524)
				(type default)
			)
			(layer "F.SilkS")
		)
		(fp_line
			(start 0.67945 0.3048)
			(end 0.120396 0.3048)
			(stroke
				(width 0.1)
				(type default)
			)
			(layer "F.Fab")
		)
		(fp_line
			(start 0.67945 -0.3048)
			(end 0.67945 0.3048)
			(stroke
				(width 0.1)
				(type default)
			)
			(layer "F.Fab")
		)
		(fp_line
			(start 0.12065 -0.2794)
			(end 0.12065 -0.3048)
			(stroke
				(width 0.1)
				(type default)
			)
			(layer "F.Fab")
		)
		(fp_line
			(start 0.12065 -0.3048)
			(end 0.67945 -0.3048)
			(stroke
				(width 0.1)
				(type default)
			)
			(layer "F.Fab")
		)
		(fp_line
			(start 0.120396 0.3048)
			(end 0.120396 0.2794)
			(stroke
				(width 0.1)
				(type default)
			)
			(layer "F.Fab")
		)
		(fp_line
			(start 0.120396 0.2794)
			(end -0.12065 0.2794)
			(stroke
				(width 0.1)
				(type default)
			)
			(layer "F.Fab")
		)
		(fp_line
			(start -0.12065 0.3048)
			(end -0.67945 0.3048)
			(stroke
				(width 0.1)
				(type default)
			)
			(layer "F.Fab")
		)
		(fp_line
			(start -0.12065 0.2794)
			(end -0.12065 0.3048)
			(stroke
				(width 0.1)
				(type default)
			)
			(layer "F.Fab")
		)
		(fp_line
			(start -0.12065 -0.2794)
			(end 0.12065 -0.2794)
			(stroke
				(width 0.1)
				(type default)
			)
			(layer "F.Fab")
		)
		(fp_line
			(start -0.12065 -0.305054)
			(end -0.12065 -0.2794)
			(stroke
				(width 0.1)
				(type default)
			)
			(layer "F.Fab")
		)
		(fp_line
			(start -0.67945 0.3048)
			(end -0.67945 -0.305054)
			(stroke
				(width 0.1)
				(type default)
			)
			(layer "F.Fab")
		)
		(fp_line
			(start -0.67945 -0.305054)
			(end -0.12065 -0.305054)
			(stroke
				(width 0.1)
				(type default)
			)
			(layer "F.Fab")
		)
		(pad "1" smd circle
			(at -0.40005 0 180)
			(size 0 0)
			(layers "F.Cu" "F.Mask" "F.Paste")
			(net "P3V3_AUX")
		)
		(pad "2" smd circle
			(at 0.40005 0 180)
			(size 0 0)
			(layers "F.Cu" "F.Mask" "F.Paste")
			(net "SMB_ADC_SDA_R")
		)
	)
	(footprint ""
		(layer "F.Cu")
		(at 164.557964 -44.247054)
		(property "Reference" "R138"
			(at 0 0 0)
			(layer "F.SilkS")
			(hide yes)
			(effects
				(font
					(size 1.27 1.27)
				)
			)
		)
		(property "Value" ""
			(at 0 0 0)
			(layer "F.Fab")
			(effects
				(font
					(size 1.27 1.27)
				)
			)
		)
		(duplicate_pad_numbers_are_jumpers no)
		(fp_line
			(start -0.7874 -0.4064)
			(end 0.7874 -0.4064)
			(stroke
				(width 0.1524)
				(type default)
			)
			(layer "F.SilkS")
		)
		(fp_line
			(start -0.7874 0.4064)
			(end -0.7874 -0.4064)
			(stroke
				(width 0.1524)
				(type default)
			)
			(layer "F.SilkS")
		)
		(fp_line
			(start 0.7874 -0.4064)
			(end 0.7874 0.4064)
			(stroke
				(width 0.1524)
				(type default)
			)
			(layer "F.SilkS")
		)
		(fp_line
			(start 0.7874 0.4064)
			(end -0.7874 0.4064)
			(stroke
				(width 0.1524)
				(type default)
			)
			(layer "F.SilkS")
		)
		(fp_line
			(start -0.67945 -0.305054)
			(end -0.12065 -0.305054)
			(stroke
				(width 0.1)
				(type default)
			)
			(layer "F.Fab")
		)
		(fp_line
			(start -0.67945 0.3048)
			(end -0.67945 -0.305054)
			(stroke
				(width 0.1)
				(type default)
			)
			(layer "F.Fab")
		)
		(fp_line
			(start -0.12065 -0.305054)
			(end -0.12065 -0.2794)
			(stroke
				(width 0.1)
				(type default)
			)
			(layer "F.Fab")
		)
		(fp_line
			(start -0.12065 -0.2794)
			(end 0.12065 -0.2794)
			(stroke
				(width 0.1)
				(type default)
			)
			(layer "F.Fab")
		)
		(fp_line
			(start -0.12065 0.2794)
			(end -0.12065 0.3048)
			(stroke
				(width 0.1)
				(type default)
			)
			(layer "F.Fab")
		)
		(fp_line
			(start -0.12065 0.3048)
			(end -0.67945 0.3048)
			(stroke
				(width 0.1)
				(type default)
			)
			(layer "F.Fab")
		)
		(fp_line
			(start 0.120396 0.2794)
			(end -0.12065 0.2794)
			(stroke
				(width 0.1)
				(type default)
			)
			(layer "F.Fab")
		)
		(fp_line
			(start 0.120396 0.3048)
			(end 0.120396 0.2794)
			(stroke
				(width 0.1)
				(type default)
			)
			(layer "F.Fab")
		)
		(fp_line
			(start 0.12065 -0.3048)
			(end 0.67945 -0.3048)
			(stroke
				(width 0.1)
				(type default)
			)
			(layer "F.Fab")
		)
		(fp_line
			(start 0.12065 -0.2794)
			(end 0.12065 -0.3048)
			(stroke
				(width 0.1)
				(type default)
			)
			(layer "F.Fab")
		)
		(fp_line
			(start 0.67945 -0.3048)
			(end 0.67945 0.3048)
			(stroke
				(width 0.1)
				(type default)
			)
			(layer "F.Fab")
		)
		(fp_line
			(start 0.67945 0.3048)
			(end 0.120396 0.3048)
			(stroke
				(width 0.1)
				(type default)
			)
			(layer "F.Fab")
		)
		(pad "1" smd circle
			(at -0.40005 0)
			(size 0 0)
			(layers "F.Cu" "F.Mask" "F.Paste")
			(net "M2_SSD0_CLKREQ_EN_N")
		)
		(pad "2" smd circle
			(at 0.40005 0)
			(size 0 0)
			(layers "F.Cu" "F.Mask" "F.Paste")
			(net "GND")
		)
	)
	(footprint ""
		(layer "F.Cu")
		(at 120.396 -424.688)
		(property "Reference" "R3453"
			(at 0 0 0)
			(layer "F.SilkS")
			(hide yes)
			(effects
				(font
					(size 1.27 1.27)
				)
			)
		)
		(property "Value" ""
			(at 0 0 0)
			(layer "F.Fab")
			(effects
				(font
					(size 1.27 1.27)
				)
			)
		)
		(duplicate_pad_numbers_are_jumpers no)
		(fp_line
			(start -0.7874 -0.4064)
			(end 0.7874 -0.4064)
			(stroke
				(width 0.1524)
				(type default)
			)
			(layer "F.SilkS")
		)
		(fp_line
			(start -0.7874 0.4064)
			(end -0.7874 -0.4064)
			(stroke
				(width 0.1524)
				(type default)
			)
			(layer "F.SilkS")
		)
		(fp_line
			(start 0.7874 -0.4064)
			(end 0.7874 0.4064)
			(stroke
				(width 0.1524)
				(type default)
			)
			(layer "F.SilkS")
		)
		(fp_line
			(start 0.7874 0.4064)
			(end -0.7874 0.4064)
			(stroke
				(width 0.1524)
				(type default)
			)
			(layer "F.SilkS")
		)
		(fp_line
			(start -0.67945 -0.305054)
			(end -0.12065 -0.305054)
			(stroke
				(width 0.1)
				(type default)
			)
			(layer "F.Fab")
		)
		(fp_line
			(start -0.67945 0.3048)
			(end -0.67945 -0.305054)
			(stroke
				(width 0.1)
				(type default)
			)
			(layer "F.Fab")
		)
		(fp_line
			(start -0.12065 -0.305054)
			(end -0.12065 -0.2794)
			(stroke
				(width 0.1)
				(type default)
			)
			(layer "F.Fab")
		)
		(fp_line
			(start -0.12065 -0.2794)
			(end 0.12065 -0.2794)
			(stroke
				(width 0.1)
				(type default)
			)
			(layer "F.Fab")
		)
		(fp_line
			(start -0.12065 0.2794)
			(end -0.12065 0.3048)
			(stroke
				(width 0.1)
				(type default)
			)
			(layer "F.Fab")
		)
		(fp_line
			(start -0.12065 0.3048)
			(end -0.67945 0.3048)
			(stroke
				(width 0.1)
				(type default)
			)
			(layer "F.Fab")
		)
		(fp_line
			(start 0.120396 0.2794)
			(end -0.12065 0.2794)
			(stroke
				(width 0.1)
				(type default)
			)
			(layer "F.Fab")
		)
		(fp_line
			(start 0.120396 0.3048)
			(end 0.120396 0.2794)
			(stroke
				(width 0.1)
				(type default)
			)
			(layer "F.Fab")
		)
		(fp_line
			(start 0.12065 -0.3048)
			(end 0.67945 -0.3048)
			(stroke
				(width 0.1)
				(type default)
			)
			(layer "F.Fab")
		)
		(fp_line
			(start 0.12065 -0.2794)
			(end 0.12065 -0.3048)
			(stroke
				(width 0.1)
				(type default)
			)
			(layer "F.Fab")
		)
		(fp_line
			(start 0.67945 -0.3048)
			(end 0.67945 0.3048)
			(stroke
				(width 0.1)
				(type default)
			)
			(layer "F.Fab")
		)
		(fp_line
			(start 0.67945 0.3048)
			(end 0.120396 0.3048)
			(stroke
				(width 0.1)
				(type default)
			)
			(layer "F.Fab")
		)
		(pad "1" smd circle
			(at -0.40005 0)
			(size 0 0)
			(layers "F.Cu" "F.Mask" "F.Paste")
			(net "P3V3_AUX")
		)
		(pad "2" smd circle
			(at 0.40005 0)
			(size 0 0)
			(layers "F.Cu" "F.Mask" "F.Paste")
			(net "GPU_FPGA_BOOT_EN_BUF_R")
		)
	)
)
